(kicad_pcb
	(version 20260206)
	(generator "pcbnew")
	(generator_version "10.0")
	(general
		(thickness 1.6)
		(legacy_teardrops no)
	)
	(paper "A4")
	(title_block
		(title "ptb — 12523-1.1018WZS1506.brd")
		(comment 1 "Open Vault / Knox (Wiwynn) / footprints 61-61 of 61")
	)
	(layers
		(0 "F.Cu" signal "TOP")
		(4 "In1.Cu" signal "L2GND")
		(6 "In2.Cu" signal "L3VCC")
		(2 "B.Cu" signal "BOTTOM")
		(9 "F.Adhes" user "F.Adhesive")
		(11 "B.Adhes" user "B.Adhesive")
		(13 "F.Paste" user "Package Geometry/Pastemask Top")
		(15 "B.Paste" user "Package Geometry/Pastemask Bottom")
		(5 "F.SilkS" user "Ref Des/Silkscreen Top")
		(7 "B.SilkS" user "Ref Des/Silkscreen Bottom")
		(1 "F.Mask" user "Board Geometry/Soldermask Top")
		(3 "B.Mask" user "Board Geometry/Soldermask Bottom")
		(17 "Dwgs.User" user "User.Drawings")
		(19 "Cmts.User" user "User.Comments")
		(21 "Eco1.User" user "User.Eco1")
		(23 "Eco2.User" user "User.Eco2")
		(25 "Edge.Cuts" user "Board Geometry/Outline")
		(27 "Margin" user)
		(31 "F.CrtYd" user "Package Geometry/Place Bound Top")
		(29 "B.CrtYd" user "Package Geometry/Place Bound Bottom")
		(35 "F.Fab" user "Ref Des/Assembly Top")
		(33 "B.Fab" user "Ref Des/Assembly Bottom")
	)
	(footprint ""
		(layer "F.Cu")
		(at 136.152382 -68.318634 90)
		(property "Reference" "R386"
			(at 0 0 90)
			(layer "F.SilkS")
			(hide yes)
			(effects
				(font
					(size 1.27 1.27)
				)
			)
		)
		(property "Value" "0R2J-2-GP"
			(at 0.064008 -3.993896 90)
			(unlocked yes)
			(layer "F.Fab")
			(hide yes)
			(effects
				(font
					(size 1.016 1.016)
					(thickness 0.1524)
				)
			)
		)
		(property "Device Type" "R402H16"
			(at 0.064008 -5.517896 90)
			(unlocked yes)
			(layer "F.Fab")
			(hide yes)
			(effects
				(font
					(size 1.016 1.016)
					(thickness 0.1524)
				)
			)
		)
		(duplicate_pad_numbers_are_jumpers no)
		(fp_line
			(start 0.508 -0.9398)
			(end -0.508 -0.9398)
			(stroke
				(width 0.1524)
				(type default)
			)
			(layer "F.SilkS")
		)
		(fp_line
			(start -0.508 -0.9398)
			(end -0.508 0.9398)
			(stroke
				(width 0.1524)
				(type default)
			)
			(layer "F.SilkS")
		)
		(fp_rect
			(start -0.508 0.9398)
			(end 0.508 -0.9398)
			(stroke
				(width 0)
				(type default)
			)
			(fill no)
			(layer "F.CrtYd")
		)
		(fp_rect
			(start -0.508 0.9398)
			(end 0.508 -0.9398)
			(stroke
				(width 0)
				(type default)
			)
			(fill no)
			(layer "F.Fab")
		)
		(pad "1" smd custom
			(at 0 -0.4445 90)
			(size 0.1397 0.1397)
			(layers "F.Cu" "F.Mask" "F.Paste")
			(net "I2C_C_BUF_SDA")
			(options
				(clearance outline)
				(anchor circle)
			)
			(primitives
				(gr_poly
					(pts
						(arc
							(start -0.1778 -0.2794)
							(mid -0.249642 -0.249642)
							(end -0.2794 -0.1778)
						)
						(arc
							(start -0.2794 0.1778)
							(mid -0.249642 0.249642)
							(end -0.1778 0.2794)
						)
						(arc
							(start 0.1778 0.2794)
							(mid 0.249642 0.249642)
							(end 0.2794 0.1778)
						)
						(arc
							(start 0.2794 -0.1778)
							(mid 0.249642 -0.249642)
							(end 0.1778 -0.2794)
						)
					)
					(width 0)
					(fill yes)
				)
			)
		)
		(pad "2" smd custom
			(at 0 0.4445 90)
			(size 0.1397 0.1397)
			(layers "F.Cu" "F.Mask" "F.Paste")
			(net "I2C_C_BUF_SDA_CONN")
			(options
				(clearance outline)
				(anchor circle)
			)
			(primitives
				(gr_poly
					(pts
						(arc
							(start -0.1778 -0.2794)
							(mid -0.249642 -0.249642)
							(end -0.2794 -0.1778)
						)
						(arc
							(start -0.2794 0.1778)
							(mid -0.249642 0.249642)
							(end -0.1778 0.2794)
						)
						(arc
							(start 0.1778 0.2794)
							(mid 0.249642 0.249642)
							(end 0.2794 0.1778)
						)
						(arc
							(start 0.2794 -0.1778)
							(mid 0.249642 -0.249642)
							(end 0.1778 -0.2794)
						)
					)
					(width 0)
					(fill yes)
				)
			)
		)
	)
)
